(kicad_pcb
	(version 20260206)
	(generator "pcbnew")
	(generator_version "10.0")
	(general
		(thickness 1.6)
		(legacy_teardrops no)
	)
	(paper "A4")
	(title_block
		(title "peb — Lightning_PEB_BRD.brd")
		(comment 1 "Lightning (Wiwynn / Facebook NVMe JBOF) / footprints 2175-2183 of 2563")
	)
	(layers
		(0 "F.Cu" signal "TOP")
		(4 "In1.Cu" signal "L2GND")
		(6 "In2.Cu" signal "L3")
		(8 "In3.Cu" signal "L4VCC")
		(10 "In4.Cu" signal "L5VCC")
		(12 "In5.Cu" signal "L6")
		(14 "In6.Cu" signal "L7GND")
		(2 "B.Cu" signal "BOTTOM")
		(9 "F.Adhes" user "F.Adhesive")
		(11 "B.Adhes" user "B.Adhesive")
		(13 "F.Paste" user "Package Geometry/Pastemask Top")
		(15 "B.Paste" user "Package Geometry/Pastemask Bottom")
		(5 "F.SilkS" user "Ref Des/Silkscreen Top")
		(7 "B.SilkS" user "Ref Des/Silkscreen Bottom")
		(1 "F.Mask" user "Board Geometry/Soldermask Top")
		(3 "B.Mask" user "Board Geometry/Soldermask Bottom")
		(17 "Dwgs.User" user "User.Drawings")
		(19 "Cmts.User" user "User.Comments")
		(21 "Eco1.User" user "User.Eco1")
		(23 "Eco2.User" user "User.Eco2")
		(25 "Edge.Cuts" user "Board Geometry/Outline")
		(27 "Margin" user)
		(31 "F.CrtYd" user "Package Geometry/Place Bound Top")
		(29 "B.CrtYd" user "Package Geometry/Place Bound Bottom")
		(35 "F.Fab" user "Ref Des/Assembly Top")
		(33 "B.Fab" user "Ref Des/Assembly Bottom")
	)
	(footprint ""
		(layer "B.Cu")
		(at 270.18615 -11.258042 90)
		(property "Reference" "R2963"
			(at 0 0 90)
			(layer "B.SilkS")
			(hide yes)
			(effects
				(font
					(size 1.27 1.27)
				)
				(justify mirror)
			)
		)
		(property "Value" "0R2J-2-GP"
			(at -0.064008 -3.993896 90)
			(unlocked yes)
			(layer "B.Fab")
			(hide yes)
			(effects
				(font
					(size 1.016 1.016)
					(thickness 0.1524)
				)
				(justify mirror)
			)
		)
		(property "Device Type" "R402H16"
			(at -0.064008 -5.517896 90)
			(unlocked yes)
			(layer "B.Fab")
			(hide yes)
			(effects
				(font
					(size 1.016 1.016)
					(thickness 0.1524)
				)
				(justify mirror)
			)
		)
		(duplicate_pad_numbers_are_jumpers no)
		(fp_line
			(start 0.508 -0.9398)
			(end 0.508 0.9398)
			(stroke
				(width 0.1524)
				(type default)
			)
			(layer "B.SilkS")
		)
		(fp_line
			(start -0.508 -0.9398)
			(end 0.508 -0.9398)
			(stroke
				(width 0.1524)
				(type default)
			)
			(layer "B.SilkS")
		)
		(fp_rect
			(start 0.508 0.9398)
			(end -0.508 -0.9398)
			(stroke
				(width 0)
				(type default)
			)
			(fill no)
			(layer "B.CrtYd")
		)
		(fp_rect
			(start 0.508 0.9398)
			(end -0.508 -0.9398)
			(stroke
				(width 0)
				(type default)
			)
			(fill no)
			(layer "B.Fab")
		)
		(pad "1" smd custom
			(at 0 -0.4445 270)
			(size 0.1397 0.1397)
			(layers "B.Cu" "B.Mask" "B.Paste")
			(net "HOST6_RST_N")
			(options
				(clearance outline)
				(anchor circle)
			)
			(primitives
				(gr_poly
					(pts
						(arc
							(start -0.1778 0.2794)
							(mid -0.249642 0.249642)
							(end -0.2794 0.1778)
						)
						(arc
							(start -0.2794 -0.1778)
							(mid -0.249642 -0.249642)
							(end -0.1778 -0.2794)
						)
						(arc
							(start 0.1778 -0.2794)
							(mid 0.249642 -0.249642)
							(end 0.2794 -0.1778)
						)
						(arc
							(start 0.2794 0.1778)
							(mid 0.249642 0.249642)
							(end 0.1778 0.2794)
						)
					)
					(width 0)
					(fill yes)
				)
			)
		)
		(pad "2" smd custom
			(at 0 0.4445 270)
			(size 0.1397 0.1397)
			(layers "B.Cu" "B.Mask" "B.Paste")
			(net "HOST6_RST_N_C")
			(options
				(clearance outline)
				(anchor circle)
			)
			(primitives
				(gr_poly
					(pts
						(arc
							(start -0.1778 0.2794)
							(mid -0.249642 0.249642)
							(end -0.2794 0.1778)
						)
						(arc
							(start -0.2794 -0.1778)
							(mid -0.249642 -0.249642)
							(end -0.1778 -0.2794)
						)
						(arc
							(start 0.1778 -0.2794)
							(mid 0.249642 -0.249642)
							(end 0.2794 -0.1778)
						)
						(arc
							(start 0.2794 0.1778)
							(mid 0.249642 0.249642)
							(end 0.1778 0.2794)
						)
					)
					(width 0)
					(fill yes)
				)
			)
		)
	)
	(footprint ""
		(layer "B.Cu")
		(at 58.039 -37.211)
		(property "Reference" "PC26"
			(at 0 0 0)
			(layer "B.SilkS")
			(hide yes)
			(effects
				(font
					(size 1.27 1.27)
				)
				(justify mirror)
			)
		)
		(property "Value" "SC4D7U25V5KX-1-GP"
			(at 0.0762 -6.1214 0)
			(unlocked yes)
			(layer "B.Fab")
			(hide yes)
			(effects
				(font
					(size 1.016 1.016)
					(thickness 0.1524)
				)
				(justify mirror)
			)
		)
		(property "Device Type" "C805H58"
			(at 0.0762 -8.1534 0)
			(unlocked yes)
			(layer "B.Fab")
			(hide yes)
			(effects
				(font
					(size 1.016 1.016)
					(thickness 0.1524)
				)
				(justify mirror)
			)
		)
		(duplicate_pad_numbers_are_jumpers no)
		(fp_line
			(start -0.635 0)
			(end 0.635 0)
			(stroke
				(width 0.508)
				(type default)
			)
			(layer "B.SilkS")
		)
		(fp_rect
			(start 0.9652 1.778)
			(end -0.9652 -1.778)
			(stroke
				(width 0)
				(type default)
			)
			(fill no)
			(layer "B.CrtYd")
		)
		(fp_poly
			(pts
				(xy 0.9652 -1.778) (xy -0.9652 -1.778) (xy -0.9652 1.778) (xy 0.9652 1.778)
			)
			(stroke
				(width 0)
				(type default)
			)
			(fill no)
			(layer "B.Fab")
		)
		(pad "1" smd rect
			(at 0 -0.9652 180)
			(size 1.397 1.143)
			(layers "B.Cu" "B.Mask" "B.Paste")
			(net "P3V3_STBY_VDD")
		)
		(pad "2" smd rect
			(at 0 0.9652 180)
			(size 1.397 1.143)
			(layers "B.Cu" "B.Mask" "B.Paste")
			(net "GND")
		)
	)
	(footprint ""
		(layer "B.Cu")
		(at 232.537 -20.447)
		(property "Reference" "R819"
			(at 0 0 0)
			(layer "B.SilkS")
			(hide yes)
			(effects
				(font
					(size 1.27 1.27)
				)
				(justify mirror)
			)
		)
		(property "Value" "4K7R2F-GP"
			(at -0.064008 -3.993896 0)
			(unlocked yes)
			(layer "B.Fab")
			(hide yes)
			(effects
				(font
					(size 1.016 1.016)
					(thickness 0.1524)
				)
				(justify mirror)
			)
		)
		(property "Device Type" "R402H16"
			(at -0.064008 -5.517896 0)
			(unlocked yes)
			(layer "B.Fab")
			(hide yes)
			(effects
				(font
					(size 1.016 1.016)
					(thickness 0.1524)
				)
				(justify mirror)
			)
		)
		(duplicate_pad_numbers_are_jumpers no)
		(fp_line
			(start -0.508 -0.9398)
			(end 0.508 -0.9398)
			(stroke
				(width 0.1524)
				(type default)
			)
			(layer "B.SilkS")
		)
		(fp_line
			(start 0.508 -0.9398)
			(end 0.508 0.9398)
			(stroke
				(width 0.1524)
				(type default)
			)
			(layer "B.SilkS")
		)
		(fp_rect
			(start 0.508 0.9398)
			(end -0.508 -0.9398)
			(stroke
				(width 0)
				(type default)
			)
			(fill no)
			(layer "B.CrtYd")
		)
		(fp_rect
			(start 0.508 0.9398)
			(end -0.508 -0.9398)
			(stroke
				(width 0)
				(type default)
			)
			(fill no)
			(layer "B.Fab")
		)
		(pad "1" smd custom
			(at 0 -0.4445 180)
			(size 0.1397 0.1397)
			(layers "B.Cu" "B.Mask" "B.Paste")
			(net "BOOTSTRAP9")
			(options
				(clearance outline)
				(anchor circle)
			)
			(primitives
				(gr_poly
					(pts
						(arc
							(start -0.1778 0.2794)
							(mid -0.249642 0.249642)
							(end -0.2794 0.1778)
						)
						(arc
							(start -0.2794 -0.1778)
							(mid -0.249642 -0.249642)
							(end -0.1778 -0.2794)
						)
						(arc
							(start 0.1778 -0.2794)
							(mid 0.249642 -0.249642)
							(end 0.2794 -0.1778)
						)
						(arc
							(start 0.2794 0.1778)
							(mid 0.249642 0.249642)
							(end 0.1778 0.2794)
						)
					)
					(width 0)
					(fill yes)
				)
			)
		)
		(pad "2" smd custom
			(at 0 0.4445 180)
			(size 0.1397 0.1397)
			(layers "B.Cu" "B.Mask" "B.Paste")
			(net "DUT_VDDO")
			(options
				(clearance outline)
				(anchor circle)
			)
			(primitives
				(gr_poly
					(pts
						(arc
							(start -0.1778 0.2794)
							(mid -0.249642 0.249642)
							(end -0.2794 0.1778)
						)
						(arc
							(start -0.2794 -0.1778)
							(mid -0.249642 -0.249642)
							(end -0.1778 -0.2794)
						)
						(arc
							(start 0.1778 -0.2794)
							(mid 0.249642 -0.249642)
							(end 0.2794 -0.1778)
						)
						(arc
							(start 0.2794 0.1778)
							(mid 0.249642 0.249642)
							(end 0.1778 0.2794)
						)
					)
					(width 0)
					(fill yes)
				)
			)
		)
	)
	(footprint ""
		(layer "B.Cu")
		(at 132.5626 -196.3674)
		(property "Reference" "R4126"
			(at 0 0 0)
			(layer "B.SilkS")
			(hide yes)
			(effects
				(font
					(size 1.27 1.27)
				)
				(justify mirror)
			)
		)
		(property "Value" "4K7R2F-GP"
			(at -0.064008 -3.993896 0)
			(unlocked yes)
			(layer "B.Fab")
			(hide yes)
			(effects
				(font
					(size 1.016 1.016)
					(thickness 0.1524)
				)
				(justify mirror)
			)
		)
		(property "Device Type" "R402H16"
			(at -0.064008 -5.517896 0)
			(unlocked yes)
			(layer "B.Fab")
			(hide yes)
			(effects
				(font
					(size 1.016 1.016)
					(thickness 0.1524)
				)
				(justify mirror)
			)
		)
		(duplicate_pad_numbers_are_jumpers no)
		(fp_line
			(start -0.508 -0.9398)
			(end 0.508 -0.9398)
			(stroke
				(width 0.1524)
				(type default)
			)
			(layer "B.SilkS")
		)
		(fp_line
			(start 0.508 -0.9398)
			(end 0.508 0.9398)
			(stroke
				(width 0.1524)
				(type default)
			)
			(layer "B.SilkS")
		)
		(fp_rect
			(start 0.508 0.9398)
			(end -0.508 -0.9398)
			(stroke
				(width 0)
				(type default)
			)
			(fill no)
			(layer "B.CrtYd")
		)
		(fp_rect
			(start 0.508 0.9398)
			(end -0.508 -0.9398)
			(stroke
				(width 0)
				(type default)
			)
			(fill no)
			(layer "B.Fab")
		)
		(pad "1" smd custom
			(at 0 -0.4445 180)
			(size 0.1397 0.1397)
			(layers "B.Cu" "B.Mask" "B.Paste")
			(net "SSD_ATNLED#2")
			(options
				(clearance outline)
				(anchor circle)
			)
			(primitives
				(gr_poly
					(pts
						(arc
							(start -0.1778 0.2794)
							(mid -0.249642 0.249642)
							(end -0.2794 0.1778)
						)
						(arc
							(start -0.2794 -0.1778)
							(mid -0.249642 -0.249642)
							(end -0.1778 -0.2794)
						)
						(arc
							(start 0.1778 -0.2794)
							(mid 0.249642 -0.249642)
							(end 0.2794 -0.1778)
						)
						(arc
							(start 0.2794 0.1778)
							(mid 0.249642 0.249642)
							(end 0.1778 0.2794)
						)
					)
					(width 0)
					(fill yes)
				)
			)
		)
		(pad "2" smd custom
			(at 0 0.4445 180)
			(size 0.1397 0.1397)
			(layers "B.Cu" "B.Mask" "B.Paste")
			(net "P3V3_STBY")
			(options
				(clearance outline)
				(anchor circle)
			)
			(primitives
				(gr_poly
					(pts
						(arc
							(start -0.1778 0.2794)
							(mid -0.249642 0.249642)
							(end -0.2794 0.1778)
						)
						(arc
							(start -0.2794 -0.1778)
							(mid -0.249642 -0.249642)
							(end -0.1778 -0.2794)
						)
						(arc
							(start 0.1778 -0.2794)
							(mid 0.249642 -0.249642)
							(end 0.2794 -0.1778)
						)
						(arc
							(start 0.2794 0.1778)
							(mid 0.249642 0.249642)
							(end 0.1778 0.2794)
						)
					)
					(width 0)
					(fill yes)
				)
			)
		)
	)
	(footprint ""
		(layer "B.Cu")
		(at 316.103 -68.58 180)
		(property "Reference" "PC179"
			(at 0 0 0)
			(layer "B.SilkS")
			(hide yes)
			(effects
				(font
					(size 1.27 1.27)
				)
				(justify mirror)
			)
		)
		(property "Value" "SC22U6D3V5MX-5-GP"
			(at 0.0762 -6.1214 180)
			(unlocked yes)
			(layer "B.Fab")
			(hide yes)
			(effects
				(font
					(size 1.016 1.016)
					(thickness 0.1524)
				)
				(justify mirror)
			)
		)
		(property "Device Type" "C805H56"
			(at 0.0762 -8.1534 180)
			(unlocked yes)
			(layer "B.Fab")
			(hide yes)
			(effects
				(font
					(size 1.016 1.016)
					(thickness 0.1524)
				)
				(justify mirror)
			)
		)
		(duplicate_pad_numbers_are_jumpers no)
		(fp_line
			(start -0.635 0)
			(end 0.635 0)
			(stroke
				(width 0.508)
				(type default)
			)
			(layer "B.SilkS")
		)
		(fp_rect
			(start 0.9652 1.778)
			(end -0.9652 -1.778)
			(stroke
				(width 0)
				(type default)
			)
			(fill no)
			(layer "B.CrtYd")
		)
		(fp_poly
			(pts
				(xy 0.9652 -1.778) (xy -0.9652 -1.778) (xy -0.9652 1.778) (xy 0.9652 1.778)
			)
			(stroke
				(width 0)
				(type default)
			)
			(fill no)
			(layer "B.Fab")
		)
		(pad "1" smd rect
			(at 0 -0.9652)
			(size 1.397 1.143)
			(layers "B.Cu" "B.Mask" "B.Paste")
			(net "P0V9_E")
		)
		(pad "2" smd rect
			(at 0 0.9652)
			(size 1.397 1.143)
			(layers "B.Cu" "B.Mask" "B.Paste")
			(net "GND")
		)
	)
	(footprint ""
		(layer "B.Cu")
		(at 243.459 -32.004 90)
		(property "Reference" "C473"
			(at 0 0 90)
			(layer "B.SilkS")
			(hide yes)
			(effects
				(font
					(size 1.27 1.27)
				)
				(justify mirror)
			)
		)
		(property "Value" "SCD1U16V1KX-1-GP"
			(at 2.8321 -1.7399 90)
			(unlocked yes)
			(layer "B.Fab")
			(hide yes)
			(effects
				(font
					(size 1.016 1.016)
					(thickness 0.1524)
				)
				(justify mirror)
			)
		)
		(property "Device Type" "C0201H13"
			(at 2.8321 -3.2639 90)
			(unlocked yes)
			(layer "B.Fab")
			(hide yes)
			(effects
				(font
					(size 1.016 1.016)
					(thickness 0.1524)
				)
				(justify mirror)
			)
		)
		(duplicate_pad_numbers_are_jumpers no)
		(fp_rect
			(start 0.2794 0.6477)
			(end -0.2794 -0.6477)
			(stroke
				(width 0)
				(type default)
			)
			(fill no)
			(layer "B.CrtYd")
		)
		(fp_rect
			(start 0.2794 0.6477)
			(end -0.2794 -0.6477)
			(stroke
				(width 0)
				(type default)
			)
			(fill no)
			(layer "B.Fab")
		)
		(pad "1" smd custom
			(at 0 -0.2794 270)
			(size 0.0762 0.0762)
			(layers "B.Cu" "B.Mask" "B.Paste")
			(net "DUT_VDDO")
			(options
				(clearance outline)
				(anchor circle)
			)
			(primitives
				(gr_poly
					(pts
						(arc
							(start 0.1524 0.127)
							(mid 0.137521 0.162921)
							(end 0.1016 0.1778)
						)
						(arc
							(start -0.1016 0.1778)
							(mid -0.137521 0.162921)
							(end -0.1524 0.127)
						)
						(arc
							(start -0.1524 -0.127)
							(mid -0.137521 -0.162921)
							(end -0.1016 -0.1778)
						)
						(arc
							(start 0.1016 -0.1778)
							(mid 0.137521 -0.162921)
							(end 0.1524 -0.127)
						)
					)
					(width 0)
					(fill yes)
				)
			)
		)
		(pad "2" smd custom
			(at 0 0.2794 270)
			(size 0.0762 0.0762)
			(layers "B.Cu" "B.Mask" "B.Paste")
			(net "GND")
			(options
				(clearance outline)
				(anchor circle)
			)
			(primitives
				(gr_poly
					(pts
						(arc
							(start 0.1524 0.127)
							(mid 0.137521 0.162921)
							(end 0.1016 0.1778)
						)
						(arc
							(start -0.1016 0.1778)
							(mid -0.137521 0.162921)
							(end -0.1524 0.127)
						)
						(arc
							(start -0.1524 -0.127)
							(mid -0.137521 -0.162921)
							(end -0.1016 -0.1778)
						)
						(arc
							(start 0.1016 -0.1778)
							(mid 0.137521 -0.162921)
							(end 0.1524 -0.127)
						)
					)
					(width 0)
					(fill yes)
				)
			)
		)
	)
	(footprint ""
		(layer "B.Cu")
		(at 234.823 -23.241 180)
		(property "Reference" "R784"
			(at 0 0 0)
			(layer "B.SilkS")
			(hide yes)
			(effects
				(font
					(size 1.27 1.27)
				)
				(justify mirror)
			)
		)
		(property "Value" "4K7R2F-GP"
			(at -0.064008 -3.993896 180)
			(unlocked yes)
			(layer "B.Fab")
			(hide yes)
			(effects
				(font
					(size 1.016 1.016)
					(thickness 0.1524)
				)
				(justify mirror)
			)
		)
		(property "Device Type" "R402H16"
			(at -0.064008 -5.517896 180)
			(unlocked yes)
			(layer "B.Fab")
			(hide yes)
			(effects
				(font
					(size 1.016 1.016)
					(thickness 0.1524)
				)
				(justify mirror)
			)
		)
		(duplicate_pad_numbers_are_jumpers no)
		(fp_line
			(start 0.508 -0.9398)
			(end 0.508 0.9398)
			(stroke
				(width 0.1524)
				(type default)
			)
			(layer "B.SilkS")
		)
		(fp_line
			(start -0.508 -0.9398)
			(end 0.508 -0.9398)
			(stroke
				(width 0.1524)
				(type default)
			)
			(layer "B.SilkS")
		)
		(fp_rect
			(start 0.508 0.9398)
			(end -0.508 -0.9398)
			(stroke
				(width 0)
				(type default)
			)
			(fill no)
			(layer "B.CrtYd")
		)
		(fp_rect
			(start 0.508 0.9398)
			(end -0.508 -0.9398)
			(stroke
				(width 0)
				(type default)
			)
			(fill no)
			(layer "B.Fab")
		)
		(pad "1" smd custom
			(at 0 -0.4445)
			(size 0.1397 0.1397)
			(layers "B.Cu" "B.Mask" "B.Paste")
			(net "BOOTSTRAP4")
			(options
				(clearance outline)
				(anchor circle)
			)
			(primitives
				(gr_poly
					(pts
						(arc
							(start -0.1778 0.2794)
							(mid -0.249642 0.249642)
							(end -0.2794 0.1778)
						)
						(arc
							(start -0.2794 -0.1778)
							(mid -0.249642 -0.249642)
							(end -0.1778 -0.2794)
						)
						(arc
							(start 0.1778 -0.2794)
							(mid 0.249642 -0.249642)
							(end 0.2794 -0.1778)
						)
						(arc
							(start 0.2794 0.1778)
							(mid 0.249642 0.249642)
							(end 0.1778 0.2794)
						)
					)
					(width 0)
					(fill yes)
				)
			)
		)
		(pad "2" smd custom
			(at 0 0.4445)
			(size 0.1397 0.1397)
			(layers "B.Cu" "B.Mask" "B.Paste")
			(net "BOOTSTRAP_R_4")
			(options
				(clearance outline)
				(anchor circle)
			)
			(primitives
				(gr_poly
					(pts
						(arc
							(start -0.1778 0.2794)
							(mid -0.249642 0.249642)
							(end -0.2794 0.1778)
						)
						(arc
							(start -0.2794 -0.1778)
							(mid -0.249642 -0.249642)
							(end -0.1778 -0.2794)
						)
						(arc
							(start 0.1778 -0.2794)
							(mid 0.249642 -0.249642)
							(end 0.2794 -0.1778)
						)
						(arc
							(start 0.2794 0.1778)
							(mid 0.249642 0.249642)
							(end 0.1778 0.2794)
						)
					)
					(width 0)
					(fill yes)
				)
			)
		)
	)
	(footprint ""
		(layer "B.Cu")
		(at 243.59997 -38.999922 -90)
		(property "Reference" "TP239"
			(at 0 0 90)
			(layer "B.SilkS")
			(hide yes)
			(effects
				(font
					(size 1.27 1.27)
				)
				(justify mirror)
			)
		)
		(property "Value" "TPAD28-2-GP"
			(at 0.0127 -1.6637 270)
			(unlocked yes)
			(layer "B.Fab")
			(hide yes)
			(effects
				(font
					(size 1.016 1.016)
					(thickness 0.1524)
				)
				(justify mirror)
			)
		)
		(property "Device Type" "TPAD28"
			(at 0.0127 -3.1877 270)
			(unlocked yes)
			(layer "B.Fab")
			(hide yes)
			(effects
				(font
					(size 1.016 1.016)
					(thickness 0.1524)
				)
				(justify mirror)
			)
		)
		(duplicate_pad_numbers_are_jumpers no)
		(fp_poly
			(pts
				(arc
					(start 0 -0.3556)
					(mid 0 0.3556)
					(end 0 -0.3556)
				)
			)
			(stroke
				(width 0)
				(type default)
			)
			(fill no)
			(layer "B.CrtYd")
		)
		(fp_poly
			(pts
				(arc
					(start 0 -0.6096)
					(mid 0 0.6096)
					(end 0 -0.6096)
				)
			)
			(stroke
				(width 0)
				(type default)
			)
			(fill no)
			(layer "B.Fab")
		)
		(pad "1" smd circle
			(at 0 0 90)
			(size 0.7112 0.7112)
			(layers "B.Cu" "B.Mask" "B.Paste")
			(net "RS232_URTSB0")
		)
	)
	(footprint ""
		(layer "B.Cu")
		(at 184.0484 -61.595)
		(property "Reference" "C584"
			(at 0 0 0)
			(layer "B.SilkS")
			(hide yes)
			(effects
				(font
					(size 1.27 1.27)
				)
				(justify mirror)
			)
		)
		(property "Value" "SC4D7U16V5KX-1-GP"
			(at 0.0762 -6.1214 0)
			(unlocked yes)
			(layer "B.Fab")
			(hide yes)
			(effects
				(font
					(size 1.016 1.016)
					(thickness 0.1524)
				)
				(justify mirror)
			)
		)
		(property "Device Type" "C805H56"
			(at 0.0762 -8.1534 0)
			(unlocked yes)
			(layer "B.Fab")
			(hide yes)
			(effects
				(font
					(size 1.016 1.016)
					(thickness 0.1524)
				)
				(justify mirror)
			)
		)
		(duplicate_pad_numbers_are_jumpers no)
		(fp_line
			(start -0.635 0)
			(end 0.635 0)
			(stroke
				(width 0.508)
				(type default)
			)
			(layer "B.SilkS")
		)
		(fp_rect
			(start 0.9652 1.778)
			(end -0.9652 -1.778)
			(stroke
				(width 0)
				(type default)
			)
			(fill no)
			(layer "B.CrtYd")
		)
		(fp_poly
			(pts
				(xy 0.9652 -1.778) (xy -0.9652 -1.778) (xy -0.9652 1.778) (xy 0.9652 1.778)
			)
			(stroke
				(width 0)
				(type default)
			)
			(fill no)
			(layer "B.Fab")
		)
		(pad "1" smd rect
			(at 0 -0.9652 180)
			(size 1.397 1.143)
			(layers "B.Cu" "B.Mask" "B.Paste")
			(net "DUT_AVD_PCIE")
		)
		(pad "2" smd rect
			(at 0 0.9652 180)
			(size 1.397 1.143)
			(layers "B.Cu" "B.Mask" "B.Paste")
			(net "GND")
		)
	)
)
